(kicad_pcb
	(version 20260206)
	(generator "pcbnew")
	(generator_version "10.0")
	(general
		(thickness 1.6)
		(legacy_teardrops no)
	)
	(paper "A4")
	(title_block
		(title "04192023_DAF0TMB3IC0_F0TG_MB_C_brd_V02_OCP.brd")
		(comment 1 "Grand Teton / footprint 2783 of 8354 (U26), pads 3337-3446 of 6102")
	)
	(layers
		(0 "F.Cu" signal "TOP")
		(4 "In1.Cu" signal "GND")
		(6 "In2.Cu" signal "IN1")
		(8 "In3.Cu" signal "GND1")
		(10 "In4.Cu" signal "IN2")
		(12 "In5.Cu" signal "GND2")
		(14 "In6.Cu" signal "IN3")
		(16 "In7.Cu" signal "GND3")
		(18 "In8.Cu" signal "VCC")
		(20 "In9.Cu" signal "VCC1")
		(22 "In10.Cu" signal "GND4")
		(24 "In11.Cu" signal "IN4")
		(26 "In12.Cu" signal "GND5")
		(28 "In13.Cu" signal "IN5")
		(30 "In14.Cu" signal "GND6")
		(32 "In15.Cu" signal "IN6")
		(34 "In16.Cu" signal "GND7")
		(2 "B.Cu" signal "BOTTOM")
		(9 "F.Adhes" user "F.Adhesive")
		(11 "B.Adhes" user "B.Adhesive")
		(13 "F.Paste" user "Package Geometry/Pastemask Top")
		(15 "B.Paste" user "Package Geometry/Pastemask Bottom")
		(5 "F.SilkS" user "Ref Des/Silkscreen Top")
		(7 "B.SilkS" user "Ref Des/Silkscreen Bottom")
		(1 "F.Mask" user "Board Geometry/Soldermask Top")
		(3 "B.Mask" user "Board Geometry/Soldermask Bottom")
		(17 "Dwgs.User" user "User.Drawings")
		(19 "Cmts.User" user "User.Comments")
		(21 "Eco1.User" user "User.Eco1")
		(23 "Eco2.User" user "User.Eco2")
		(25 "Edge.Cuts" user "Board Geometry/Outline")
		(27 "Margin" user)
		(31 "F.CrtYd" user "Package Geometry/Place Bound Top")
		(29 "B.CrtYd" user "Package Geometry/Place Bound Bottom")
		(35 "F.Fab" user "Ref Des/Assembly Top")
		(33 "B.Fab" user "Ref Des/Assembly Bottom")
	)
	(footprint ""
		(layer "F.Cu")
		(at 111.927894 -258.880356 180)
		(property "Reference" "U26"
			(at -45.05579 -61.794136 0)
			(unlocked yes)
			(layer "F.SilkS")
			(effects
				(font
					(size 0.7874 0.5842)
					(thickness 0.1524)
				)
			)
		)
		(property "Value" ""
			(at 0 0 180)
			(layer "F.Fab")
			(effects
				(font
					(size 1.27 1.27)
				)
			)
		)
		(duplicate_pad_numbers_are_jumpers no)
		(pad "CH26" smd circle
			(at -11.43 19.800062 180)
			(size 0.450088 0.450088)
			(layers "F.Cu" "F.Mask" "F.Paste")
			(net "PVDDCR_CPU1_P1")
		)
		(pad "CH27" smd circle
			(at -10.489946 19.800062 180)
			(size 0.450088 0.450088)
			(layers "F.Cu" "F.Mask" "F.Paste")
			(net "PVDDCR_CPU1_P1")
		)
		(pad "CH28" smd circle
			(at -9.549892 19.800062 180)
			(size 0.450088 0.450088)
			(layers "F.Cu" "F.Mask" "F.Paste")
			(net "GND")
		)
		(pad "CH29" smd circle
			(at -8.610092 19.800062 180)
			(size 0.450088 0.450088)
			(layers "F.Cu" "F.Mask" "F.Paste")
			(net "PVDDCR_CPU1_P1")
		)
		(pad "CH30" smd circle
			(at -7.670038 19.800062 180)
			(size 0.450088 0.450088)
			(layers "F.Cu" "F.Mask" "F.Paste")
			(net "PVDDCR_CPU1_P1")
		)
		(pad "CH31" smd circle
			(at -6.729984 19.800062 180)
			(size 0.450088 0.450088)
			(layers "F.Cu" "F.Mask" "F.Paste")
			(net "GND")
		)
		(pad "CH32" smd circle
			(at -5.78993 19.800062 180)
			(size 0.450088 0.450088)
			(layers "F.Cu" "F.Mask" "F.Paste")
			(net "PVDDCR_CPU1_P1")
		)
		(pad "CH33" smd circle
			(at -4.849876 19.800062 180)
			(size 0.450088 0.450088)
			(layers "F.Cu" "F.Mask" "F.Paste")
			(net "PVDDCR_CPU1_P1")
		)
		(pad "CH34" smd circle
			(at -3.910076 19.800062 180)
			(size 0.450088 0.450088)
			(layers "F.Cu" "F.Mask" "F.Paste")
			(net "GND")
		)
		(pad "CH35" smd circle
			(at -2.970022 19.800062 180)
			(size 0.450088 0.450088)
			(layers "F.Cu" "F.Mask" "F.Paste")
			(net "P5E_CPU1_P3_TX_DN<2>")
		)
		(pad "CH36" smd circle
			(at -2.029968 19.800062 180)
			(size 0.450088 0.450088)
			(layers "F.Cu" "F.Mask" "F.Paste")
			(net "P5E_CPU1_P3_TX_DP<2>")
		)
		(pad "CH37" smd circle
			(at -1.089914 19.800062 180)
			(size 0.450088 0.450088)
			(layers "F.Cu" "F.Mask" "F.Paste")
			(net "GND")
		)
		(pad "CH39" smd circle
			(at 0.78994 19.800062 180)
			(size 0.450088 0.450088)
			(layers "F.Cu" "F.Mask" "F.Paste")
			(net "GND")
		)
		(pad "CH40" smd circle
			(at 1.729994 19.800062 180)
			(size 0.450088 0.450088)
			(layers "F.Cu" "F.Mask" "F.Paste")
			(net "P5E_CPU1_P1_RX_DP<13>")
		)
		(pad "CH41" smd circle
			(at 2.670048 19.800062 180)
			(size 0.450088 0.450088)
			(layers "F.Cu" "F.Mask" "F.Paste")
			(net "P5E_CPU1_P1_RX_DN<13>")
		)
		(pad "CH42" smd circle
			(at 3.610102 19.800062 180)
			(size 0.450088 0.450088)
			(layers "F.Cu" "F.Mask" "F.Paste")
			(net "GND")
		)
		(pad "CH43" smd circle
			(at 4.549902 19.800062 180)
			(size 0.450088 0.450088)
			(layers "F.Cu" "F.Mask" "F.Paste")
			(net "PVDDCR_CPU1_P1")
		)
		(pad "CH44" smd circle
			(at 5.489956 19.800062 180)
			(size 0.450088 0.450088)
			(layers "F.Cu" "F.Mask" "F.Paste")
			(net "PVDDCR_CPU1_P1")
		)
		(pad "CH45" smd circle
			(at 6.43001 19.800062 180)
			(size 0.450088 0.450088)
			(layers "F.Cu" "F.Mask" "F.Paste")
			(net "GND")
		)
		(pad "CH46" smd circle
			(at 7.370064 19.800062 180)
			(size 0.450088 0.450088)
			(layers "F.Cu" "F.Mask" "F.Paste")
			(net "PVDDCR_CPU1_P1")
		)
		(pad "CH47" smd circle
			(at 8.310118 19.800062 180)
			(size 0.450088 0.450088)
			(layers "F.Cu" "F.Mask" "F.Paste")
			(net "PVDDCR_CPU1_P1")
		)
		(pad "CH48" smd circle
			(at 9.249918 19.800062 180)
			(size 0.450088 0.450088)
			(layers "F.Cu" "F.Mask" "F.Paste")
			(net "GND")
		)
		(pad "CH49" smd circle
			(at 10.189972 19.800062 180)
			(size 0.450088 0.450088)
			(layers "F.Cu" "F.Mask" "F.Paste")
			(net "PVDDCR_CPU1_P1")
		)
		(pad "CH50" smd circle
			(at 11.130026 19.800062 180)
			(size 0.450088 0.450088)
			(layers "F.Cu" "F.Mask" "F.Paste")
			(net "PVDDCR_CPU1_P1")
		)
		(pad "CH51" smd circle
			(at 12.07008 19.800062 180)
			(size 0.450088 0.450088)
			(layers "F.Cu" "F.Mask" "F.Paste")
			(net "GND")
		)
		(pad "CH52" smd circle
			(at 13.00988 19.800062 180)
			(size 0.450088 0.450088)
			(layers "F.Cu" "F.Mask" "F.Paste")
			(net "PVDDCR_CPU1_P1")
		)
		(pad "CH53" smd circle
			(at 13.949934 19.800062 180)
			(size 0.450088 0.450088)
			(layers "F.Cu" "F.Mask" "F.Paste")
			(net "PVDDCR_CPU1_P1")
		)
		(pad "CH54" smd circle
			(at 14.889988 19.800062 180)
			(size 0.450088 0.450088)
			(layers "F.Cu" "F.Mask" "F.Paste")
			(net "GND")
		)
		(pad "CH55" smd circle
			(at 15.830042 19.800062 180)
			(size 0.450088 0.450088)
			(layers "F.Cu" "F.Mask" "F.Paste")
			(net "M_C_CPU1_SB_DQ<7>")
		)
		(pad "CH56" smd circle
			(at 16.770096 19.800062 180)
			(size 0.450088 0.450088)
			(layers "F.Cu" "F.Mask" "F.Paste")
			(net "M_C_CPU1_SB_DQ<8>")
		)
		(pad "CH57" smd circle
			(at 17.709896 19.800062 180)
			(size 0.450088 0.450088)
			(layers "F.Cu" "F.Mask" "F.Paste")
			(net "GND")
		)
		(pad "CH58" smd circle
			(at 18.64995 19.800062 180)
			(size 0.450088 0.450088)
			(layers "F.Cu" "F.Mask" "F.Paste")
			(net "M_D_CPU1_SB_DQ<7>")
		)
		(pad "CH59" smd circle
			(at 19.590004 19.800062 180)
			(size 0.450088 0.450088)
			(layers "F.Cu" "F.Mask" "F.Paste")
			(net "GND")
		)
		(pad "CH60" smd circle
			(at 20.530058 19.800062 180)
			(size 0.450088 0.450088)
			(layers "F.Cu" "F.Mask" "F.Paste")
			(net "M_D_CPU1_SB_DQ<8>")
		)
		(pad "CH61" smd circle
			(at 21.470112 19.800062 180)
			(size 0.450088 0.450088)
			(layers "F.Cu" "F.Mask" "F.Paste")
			(net "GND")
		)
		(pad "CH62" smd circle
			(at 22.409912 19.800062 180)
			(size 0.450088 0.450088)
			(layers "F.Cu" "F.Mask" "F.Paste")
			(net "M_B_CPU1_SB_DQ<7>")
		)
		(pad "CH63" smd circle
			(at 23.349966 19.800062 180)
			(size 0.450088 0.450088)
			(layers "F.Cu" "F.Mask" "F.Paste")
			(net "M_B_CPU1_SB_DQ<8>")
		)
		(pad "CH64" smd circle
			(at 24.29002 19.800062 180)
			(size 0.450088 0.450088)
			(layers "F.Cu" "F.Mask" "F.Paste")
			(net "GND")
		)
		(pad "CH65" smd circle
			(at 25.230074 19.800062 180)
			(size 0.450088 0.450088)
			(layers "F.Cu" "F.Mask" "F.Paste")
			(net "M_F_CPU1_SB_DQ<7>")
		)
		(pad "CH66" smd circle
			(at 26.170128 19.800062 180)
			(size 0.450088 0.450088)
			(layers "F.Cu" "F.Mask" "F.Paste")
			(net "GND")
		)
		(pad "CH67" smd circle
			(at 27.109928 19.800062 180)
			(size 0.450088 0.450088)
			(layers "F.Cu" "F.Mask" "F.Paste")
			(net "M_F_CPU1_SB_DQ<8>")
		)
		(pad "CH68" smd circle
			(at 28.049982 19.800062 180)
			(size 0.450088 0.450088)
			(layers "F.Cu" "F.Mask" "F.Paste")
			(net "GND")
		)
		(pad "CH69" smd circle
			(at 28.990036 19.800062 180)
			(size 0.450088 0.450088)
			(layers "F.Cu" "F.Mask" "F.Paste")
			(net "M_E_CPU1_SB_DQ<7>")
		)
		(pad "CH70" smd circle
			(at 29.93009 19.800062 180)
			(size 0.450088 0.450088)
			(layers "F.Cu" "F.Mask" "F.Paste")
			(net "M_E_CPU1_SB_DQ<8>")
		)
		(pad "CH71" smd circle
			(at 30.86989 19.800062 180)
			(size 0.450088 0.450088)
			(layers "F.Cu" "F.Mask" "F.Paste")
			(net "GND")
		)
		(pad "CH72" smd circle
			(at 31.809944 19.800062 180)
			(size 0.450088 0.450088)
			(layers "F.Cu" "F.Mask" "F.Paste")
			(net "M_A_CPU1_SB_DQ<7>")
		)
		(pad "CH73" smd circle
			(at 32.749998 19.800062 180)
			(size 0.450088 0.450088)
			(layers "F.Cu" "F.Mask" "F.Paste")
			(net "GND")
		)
		(pad "CH74" smd circle
			(at 33.690052 19.800062 180)
			(size 0.450088 0.450088)
			(layers "F.Cu" "F.Mask" "F.Paste")
			(net "M_A_CPU1_SB_DQ<8>")
		)
		(pad "CJ1" smd circle
			(at -34.459926 20.610068 180)
			(size 0.450088 0.450088)
			(layers "F.Cu" "F.Mask" "F.Paste")
			(net "GND")
		)
		(pad "CJ2" smd circle
			(at -33.519872 20.610068 180)
			(size 0.450088 0.450088)
			(layers "F.Cu" "F.Mask" "F.Paste")
			(net "M_G_CPU1_SB_DQ<10>")
		)
		(pad "CJ3" smd circle
			(at -32.580072 20.610068 180)
			(size 0.450088 0.450088)
			(layers "F.Cu" "F.Mask" "F.Paste")
			(net "M_G_CPU1_SB_DQ<9>")
		)
		(pad "CJ4" smd circle
			(at -31.640018 20.610068 180)
			(size 0.450088 0.450088)
			(layers "F.Cu" "F.Mask" "F.Paste")
			(net "GND")
		)
		(pad "CJ5" smd circle
			(at -30.699964 20.610068 180)
			(size 0.450088 0.450088)
			(layers "F.Cu" "F.Mask" "F.Paste")
			(net "M_K_CPU1_SB_DQ<10>")
		)
		(pad "CJ6" smd circle
			(at -29.75991 20.610068 180)
			(size 0.450088 0.450088)
			(layers "F.Cu" "F.Mask" "F.Paste")
			(net "GND")
		)
		(pad "CJ7" smd circle
			(at -28.82011 20.610068 180)
			(size 0.450088 0.450088)
			(layers "F.Cu" "F.Mask" "F.Paste")
			(net "M_K_CPU1_SB_DQ<9>")
		)
		(pad "CJ8" smd circle
			(at -27.880056 20.610068 180)
			(size 0.450088 0.450088)
			(layers "F.Cu" "F.Mask" "F.Paste")
			(net "GND")
		)
		(pad "CJ9" smd circle
			(at -26.940002 20.610068 180)
			(size 0.450088 0.450088)
			(layers "F.Cu" "F.Mask" "F.Paste")
			(net "M_L_CPU1_SB_DQ<10>")
		)
		(pad "CJ10" smd circle
			(at -25.999948 20.610068 180)
			(size 0.450088 0.450088)
			(layers "F.Cu" "F.Mask" "F.Paste")
			(net "M_L_CPU1_SB_DQ<9>")
		)
		(pad "CJ11" smd circle
			(at -25.059894 20.610068 180)
			(size 0.450088 0.450088)
			(layers "F.Cu" "F.Mask" "F.Paste")
			(net "GND")
		)
		(pad "CJ12" smd circle
			(at -24.120094 20.610068 180)
			(size 0.450088 0.450088)
			(layers "F.Cu" "F.Mask" "F.Paste")
			(net "M_H_CPU1_SB_DQ<10>")
		)
		(pad "CJ13" smd circle
			(at -23.18004 20.610068 180)
			(size 0.450088 0.450088)
			(layers "F.Cu" "F.Mask" "F.Paste")
			(net "GND")
		)
		(pad "CJ14" smd circle
			(at -22.239986 20.610068 180)
			(size 0.450088 0.450088)
			(layers "F.Cu" "F.Mask" "F.Paste")
			(net "M_H_CPU1_SB_DQ<9>")
		)
		(pad "CJ15" smd circle
			(at -21.299932 20.610068 180)
			(size 0.450088 0.450088)
			(layers "F.Cu" "F.Mask" "F.Paste")
			(net "GND")
		)
		(pad "CJ16" smd circle
			(at -20.359878 20.610068 180)
			(size 0.450088 0.450088)
			(layers "F.Cu" "F.Mask" "F.Paste")
			(net "M_J_CPU1_SB_DQ<10>")
		)
		(pad "CJ17" smd circle
			(at -19.420078 20.610068 180)
			(size 0.450088 0.450088)
			(layers "F.Cu" "F.Mask" "F.Paste")
			(net "M_J_CPU1_SB_DQ<9>")
		)
		(pad "CJ18" smd circle
			(at -18.480024 20.610068 180)
			(size 0.450088 0.450088)
			(layers "F.Cu" "F.Mask" "F.Paste")
			(net "GND")
		)
		(pad "CJ19" smd circle
			(at -17.53997 20.610068 180)
			(size 0.450088 0.450088)
			(layers "F.Cu" "F.Mask" "F.Paste")
			(net "M_I_CPU1_SB_DQ<10>")
		)
		(pad "CJ20" smd circle
			(at -16.599916 20.610068 180)
			(size 0.450088 0.450088)
			(layers "F.Cu" "F.Mask" "F.Paste")
			(net "GND")
		)
		(pad "CJ21" smd circle
			(at -15.660116 20.610068 180)
			(size 0.450088 0.450088)
			(layers "F.Cu" "F.Mask" "F.Paste")
			(net "M_I_CPU1_SB_DQ<9>")
		)
		(pad "CJ22" smd circle
			(at -14.720062 20.610068 180)
			(size 0.450088 0.450088)
			(layers "F.Cu" "F.Mask" "F.Paste")
			(net "PVDD11_S3_P1")
		)
		(pad "CJ23" smd circle
			(at -13.780008 20.610068 180)
			(size 0.450088 0.450088)
			(layers "F.Cu" "F.Mask" "F.Paste")
			(net "GND")
		)
		(pad "CJ24" smd circle
			(at -12.839954 20.610068 180)
			(size 0.450088 0.450088)
			(layers "F.Cu" "F.Mask" "F.Paste")
			(net "TP_CPU1_TEST47_CCD1")
		)
		(pad "CJ25" smd circle
			(at -11.8999 20.610068 180)
			(size 0.450088 0.450088)
			(layers "F.Cu" "F.Mask" "F.Paste")
			(net "TP_CPU1_TEST5_CCD5")
		)
		(pad "CJ26" smd circle
			(at -10.9601 20.610068 180)
			(size 0.450088 0.450088)
			(layers "F.Cu" "F.Mask" "F.Paste")
			(net "TP_CPU1_TEST4_CCD5")
		)
		(pad "CJ27" smd circle
			(at -10.020046 20.610068 180)
			(size 0.450088 0.450088)
			(layers "F.Cu" "F.Mask" "F.Paste")
			(net "TP_CPU1_TEST5_CCD1")
		)
		(pad "CJ28" smd circle
			(at -9.079992 20.610068 180)
			(size 0.450088 0.450088)
			(layers "F.Cu" "F.Mask" "F.Paste")
			(net "TP_CPU1_TEST4_CCD1")
		)
		(pad "CJ29" smd circle
			(at -8.139938 20.610068 180)
			(size 0.450088 0.450088)
			(layers "F.Cu" "F.Mask" "F.Paste")
			(net "TP_CPU1_TEST6_X3D1")
		)
		(pad "CJ30" smd circle
			(at -7.199884 20.610068 180)
			(size 0.450088 0.450088)
			(layers "F.Cu" "F.Mask" "F.Paste")
			(net "TP_CPU1_TEST6_CCD1")
		)
		(pad "CJ31" smd circle
			(at -6.260084 20.610068 180)
			(size 0.450088 0.450088)
			(layers "F.Cu" "F.Mask" "F.Paste")
			(net "GND")
		)
		(pad "CJ32" smd circle
			(at -5.32003 20.610068 180)
			(size 0.450088 0.450088)
			(layers "F.Cu" "F.Mask" "F.Paste")
			(net "P5E_CPU1_P3_TX_DN<4>")
		)
		(pad "CJ33" smd circle
			(at -4.379976 20.610068 180)
			(size 0.450088 0.450088)
			(layers "F.Cu" "F.Mask" "F.Paste")
			(net "P5E_CPU1_P3_TX_DP<4>")
		)
		(pad "CJ34" smd circle
			(at -3.439922 20.610068 180)
			(size 0.450088 0.450088)
			(layers "F.Cu" "F.Mask" "F.Paste")
			(net "GND")
		)
		(pad "CJ35" smd circle
			(at -2.500122 20.610068 180)
			(size 0.450088 0.450088)
			(layers "F.Cu" "F.Mask" "F.Paste")
			(net "GND")
		)
		(pad "CJ36" smd circle
			(at -1.560068 20.610068 180)
			(size 0.450088 0.450088)
			(layers "F.Cu" "F.Mask" "F.Paste")
			(net "GND")
		)
		(pad "CJ40" smd circle
			(at 1.260094 20.610068 180)
			(size 0.450088 0.450088)
			(layers "F.Cu" "F.Mask" "F.Paste")
			(net "GND")
		)
		(pad "CJ41" smd circle
			(at 2.199894 20.610068 180)
			(size 0.450088 0.450088)
			(layers "F.Cu" "F.Mask" "F.Paste")
			(net "GND")
		)
		(pad "CJ42" smd circle
			(at 3.139948 20.610068 180)
			(size 0.450088 0.450088)
			(layers "F.Cu" "F.Mask" "F.Paste")
			(net "GND")
		)
		(pad "CJ43" smd circle
			(at 4.080002 20.610068 180)
			(size 0.450088 0.450088)
			(layers "F.Cu" "F.Mask" "F.Paste")
			(net "P5E_CPU1_P1_RX_DP<11>")
		)
		(pad "CJ44" smd circle
			(at 5.020056 20.610068 180)
			(size 0.450088 0.450088)
			(layers "F.Cu" "F.Mask" "F.Paste")
			(net "P5E_CPU1_P1_RX_DN<11>")
		)
		(pad "CJ45" smd circle
			(at 5.96011 20.610068 180)
			(size 0.450088 0.450088)
			(layers "F.Cu" "F.Mask" "F.Paste")
			(net "GND")
		)
		(pad "CJ46" smd circle
			(at 6.89991 20.610068 180)
			(size 0.450088 0.450088)
			(layers "F.Cu" "F.Mask" "F.Paste")
			(net "TP_CPU1_TEST6_CCD2")
		)
		(pad "CJ47" smd circle
			(at 7.839964 20.610068 180)
			(size 0.450088 0.450088)
			(layers "F.Cu" "F.Mask" "F.Paste")
			(net "TP_CPU1_TEST4_CCD10")
		)
		(pad "CJ48" smd circle
			(at 8.780018 20.610068 180)
			(size 0.450088 0.450088)
			(layers "F.Cu" "F.Mask" "F.Paste")
			(net "TP_CPU1_TEST4_CCD2")
		)
		(pad "CJ49" smd circle
			(at 9.720072 20.610068 180)
			(size 0.450088 0.450088)
			(layers "F.Cu" "F.Mask" "F.Paste")
			(net "TP_CPU1_TEST5_CCD2")
		)
		(pad "CJ50" smd circle
			(at 10.659872 20.610068 180)
			(size 0.450088 0.450088)
			(layers "F.Cu" "F.Mask" "F.Paste")
			(net "TP_CPU1_TEST4_CCD6")
		)
		(pad "CJ51" smd circle
			(at 11.599926 20.610068 180)
			(size 0.450088 0.450088)
			(layers "F.Cu" "F.Mask" "F.Paste")
			(net "TP_CPU1_TEST5_CCD6")
		)
		(pad "CJ52" smd circle
			(at 12.53998 20.610068 180)
			(size 0.450088 0.450088)
			(layers "F.Cu" "F.Mask" "F.Paste")
			(net "TP_CPU1_TEST6_X3D3")
		)
		(pad "CJ53" smd circle
			(at 13.480034 20.610068 180)
			(size 0.450088 0.450088)
			(layers "F.Cu" "F.Mask" "F.Paste")
			(net "TP_CPU1_TEST6_X3D5")
		)
		(pad "CJ54" smd circle
			(at 14.420088 20.610068 180)
			(size 0.450088 0.450088)
			(layers "F.Cu" "F.Mask" "F.Paste")
			(net "PVDDIO_P1")
		)
		(pad "CJ55" smd circle
			(at 15.359888 20.610068 180)
			(size 0.450088 0.450088)
			(layers "F.Cu" "F.Mask" "F.Paste")
			(net "M_C_CPU1_SB_DQ<9>")
		)
		(pad "CJ56" smd circle
			(at 16.299942 20.610068 180)
			(size 0.450088 0.450088)
			(layers "F.Cu" "F.Mask" "F.Paste")
			(net "GND")
		)
		(pad "CJ57" smd circle
			(at 17.239996 20.610068 180)
			(size 0.450088 0.450088)
			(layers "F.Cu" "F.Mask" "F.Paste")
			(net "M_C_CPU1_SB_DQ<10>")
		)
		(pad "CJ58" smd circle
			(at 18.18005 20.610068 180)
			(size 0.450088 0.450088)
			(layers "F.Cu" "F.Mask" "F.Paste")
			(net "GND")
		)
		(pad "CJ59" smd circle
			(at 19.120104 20.610068 180)
			(size 0.450088 0.450088)
			(layers "F.Cu" "F.Mask" "F.Paste")
			(net "M_D_CPU1_SB_DQ<9>")
		)
		(pad "CJ60" smd circle
			(at 20.059904 20.610068 180)
			(size 0.450088 0.450088)
			(layers "F.Cu" "F.Mask" "F.Paste")
			(net "M_D_CPU1_SB_DQ<10>")
		)
		(pad "CJ61" smd circle
			(at 20.999958 20.610068 180)
			(size 0.450088 0.450088)
			(layers "F.Cu" "F.Mask" "F.Paste")
			(net "GND")
		)
		(pad "CJ62" smd circle
			(at 21.940012 20.610068 180)
			(size 0.450088 0.450088)
			(layers "F.Cu" "F.Mask" "F.Paste")
			(net "M_B_CPU1_SB_DQ<9>")
		)
		(pad "CJ63" smd circle
			(at 22.880066 20.610068 180)
			(size 0.450088 0.450088)
			(layers "F.Cu" "F.Mask" "F.Paste")
			(net "GND")
		)
		(pad "CJ64" smd circle
			(at 23.82012 20.610068 180)
			(size 0.450088 0.450088)
			(layers "F.Cu" "F.Mask" "F.Paste")
			(net "M_B_CPU1_SB_DQ<10>")
		)
		(pad "CJ65" smd circle
			(at 24.75992 20.610068 180)
			(size 0.450088 0.450088)
			(layers "F.Cu" "F.Mask" "F.Paste")
			(net "GND")
		)
	)
)
